(kicad_pcb
	(version 20260206)
	(generator "pcbnew")
	(generator_version "10.0")
	(general
		(thickness 1.6)
		(legacy_teardrops no)
	)
	(paper "A4")
	(title_block
		(title "03242023_DA0F0TMBIJ0_F0T_Motherboard_J_brd_V01_OCP.brd")
		(comment 1 "Grand Teton / footprint 3039 of 6105 (U2), pads 4542-4651 of 4677")
	)
	(layers
		(0 "F.Cu" signal "TOP")
		(4 "In1.Cu" signal "GND")
		(6 "In2.Cu" signal "IN1")
		(8 "In3.Cu" signal "GND1")
		(10 "In4.Cu" signal "IN2")
		(12 "In5.Cu" signal "GND2")
		(14 "In6.Cu" signal "IN3")
		(16 "In7.Cu" signal "GND3")
		(18 "In8.Cu" signal "VCC")
		(20 "In9.Cu" signal "VCC1")
		(22 "In10.Cu" signal "GND4")
		(24 "In11.Cu" signal "IN4")
		(26 "In12.Cu" signal "GND5")
		(28 "In13.Cu" signal "IN5")
		(30 "In14.Cu" signal "GND6")
		(32 "In15.Cu" signal "IN6")
		(34 "In16.Cu" signal "GND7")
		(2 "B.Cu" signal "BOTTOM")
		(9 "F.Adhes" user "F.Adhesive")
		(11 "B.Adhes" user "B.Adhesive")
		(13 "F.Paste" user "Package Geometry/Pastemask Top")
		(15 "B.Paste" user "Package Geometry/Pastemask Bottom")
		(5 "F.SilkS" user "Ref Des/Silkscreen Top")
		(7 "B.SilkS" user "Ref Des/Silkscreen Bottom")
		(1 "F.Mask" user "Board Geometry/Soldermask Top")
		(3 "B.Mask" user "Board Geometry/Soldermask Bottom")
		(17 "Dwgs.User" user "User.Drawings")
		(19 "Cmts.User" user "User.Comments")
		(21 "Eco1.User" user "User.Eco1")
		(23 "Eco2.User" user "User.Eco2")
		(25 "Edge.Cuts" user "Board Geometry/Outline")
		(27 "Margin" user)
		(31 "F.CrtYd" user "Package Geometry/Place Bound Top")
		(29 "B.CrtYd" user "Package Geometry/Place Bound Bottom")
		(35 "F.Fab" user "Ref Des/Assembly Top")
		(33 "B.Fab" user "Ref Des/Assembly Bottom")
	)
	(footprint ""
		(layer "F.Cu")
		(at 359.870248 -251.76988 90)
		(property "Reference" "U2"
			(at -74.416158 -44.488608 0)
			(unlocked yes)
			(layer "F.SilkS")
			(effects
				(font
					(size 1.6002 1.1938)
					(thickness 0.1524)
				)
				(justify left)
			)
		)
		(property "Value" ""
			(at 0 0 90)
			(layer "F.Fab")
			(effects
				(font
					(size 1.27 1.27)
				)
			)
		)
		(duplicate_pad_numbers_are_jumpers no)
		(pad "U90" smd circle
			(at 36.611306 -19.445732 270)
			(size 0.4318 0.4318)
			(layers "F.Cu" "F.Mask" "F.Paste")
			(net "P5E_CPU0_PE4_RX_DP<3>")
		)
		(pad "V2" smd circle
			(at -36.611306 -19.086068 270)
			(size 0.4318 0.4318)
			(layers "F.Cu" "F.Mask" "F.Paste")
			(net "UPI_CPU0_CPU1_P0P1_DP<4>")
		)
		(pad "V4" smd circle
			(at -34.98342 -19.086068 270)
			(size 0.4318 0.4318)
			(layers "F.Cu" "F.Mask" "F.Paste")
			(net "GND")
		)
		(pad "V6" smd circle
			(at -33.355534 -19.086068 270)
			(size 0.4318 0.4318)
			(layers "F.Cu" "F.Mask" "F.Paste")
			(net "UPI_CPU1_CPU0_P1P0_DN<4>")
		)
		(pad "V8" smd circle
			(at -31.727902 -19.086068 270)
			(size 0.4318 0.4318)
			(layers "F.Cu" "F.Mask" "F.Paste")
			(net "GND")
		)
		(pad "V10" smd circle
			(at -30.100016 -19.086068 270)
			(size 0.4318 0.4318)
			(layers "F.Cu" "F.Mask" "F.Paste")
			(net "P5E_CPU0_PE0_RX_DN<4>")
		)
		(pad "V12" smd circle
			(at -28.472384 -19.086068 270)
			(size 0.4318 0.4318)
			(layers "F.Cu" "F.Mask" "F.Paste")
			(net "GND")
		)
		(pad "V14" smd circle
			(at -26.844498 -19.086068 270)
			(size 0.4318 0.4318)
			(layers "F.Cu" "F.Mask" "F.Paste")
			(net "P5E_CPU0_PE0_TX_DN<3>")
		)
		(pad "V16" smd circle
			(at -25.216612 -19.086068 270)
			(size 0.4318 0.4318)
			(layers "F.Cu" "F.Mask" "F.Paste")
			(net "GND")
		)
		(pad "V18" smd circle
			(at -23.58898 -19.086068 270)
			(size 0.4318 0.4318)
			(layers "F.Cu" "F.Mask" "F.Paste")
			(net "GND")
		)
		(pad "V20" smd circle
			(at -21.961094 -19.086068 270)
			(size 0.4318 0.4318)
			(layers "F.Cu" "F.Mask" "F.Paste")
			(net "GND")
		)
		(pad "V22" smd circle
			(at -20.333462 -19.086068 270)
			(size 0.4318 0.4318)
			(layers "F.Cu" "F.Mask" "F.Paste")
			(net "GND")
		)
		(pad "V24" smd circle
			(at -18.705576 -19.086068 270)
			(size 0.4318 0.4318)
			(layers "F.Cu" "F.Mask" "F.Paste")
			(net "GND")
		)
		(pad "V26" smd circle
			(at -17.07769 -19.086068 270)
			(size 0.4318 0.4318)
			(layers "F.Cu" "F.Mask" "F.Paste")
			(net "GND")
		)
		(pad "V28" smd circle
			(at -15.450058 -19.086068 270)
			(size 0.4318 0.4318)
			(layers "F.Cu" "F.Mask" "F.Paste")
			(net "GND")
		)
		(pad "V30" smd circle
			(at -13.822426 -19.086068 270)
			(size 0.4318 0.4318)
			(layers "F.Cu" "F.Mask" "F.Paste")
			(net "GND")
		)
		(pad "V32" smd circle
			(at -12.19454 -19.086068 270)
			(size 0.4318 0.4318)
			(layers "F.Cu" "F.Mask" "F.Paste")
			(net "GND")
		)
		(pad "V34" smd circle
			(at -10.566654 -19.086068 270)
			(size 0.4318 0.4318)
			(layers "F.Cu" "F.Mask" "F.Paste")
			(net "GND")
		)
		(pad "V36" smd circle
			(at -8.939022 -19.086068 270)
			(size 0.4318 0.4318)
			(layers "F.Cu" "F.Mask" "F.Paste")
			(net "GND")
		)
		(pad "V38" smd circle
			(at -7.311136 -19.086068 270)
			(size 0.4318 0.4318)
			(layers "F.Cu" "F.Mask" "F.Paste")
			(net "GND")
		)
		(pad "V40" smd circle
			(at -5.68325 -19.086068 270)
			(size 0.4318 0.4318)
			(layers "F.Cu" "F.Mask" "F.Paste")
			(net "GND")
		)
		(pad "V42" smd circle
			(at -4.055618 -19.086068 270)
			(size 0.4318 0.4318)
			(layers "F.Cu" "F.Mask" "F.Paste")
			(net "GND")
		)
		(pad "V44" smd circle
			(at -2.427732 -19.086068 270)
			(size 0.4318 0.4318)
			(layers "F.Cu" "F.Mask" "F.Paste")
			(net "GND")
		)
		(pad "V47" smd circle
			(at 1.613916 -18.976086 270)
			(size 0.4318 0.4318)
			(layers "F.Cu" "F.Mask" "F.Paste")
			(net "GND")
		)
		(pad "V49" smd circle
			(at 3.241802 -18.976086 270)
			(size 0.4318 0.4318)
			(layers "F.Cu" "F.Mask" "F.Paste")
			(net "GND")
		)
		(pad "V51" smd circle
			(at 4.869434 -18.976086 270)
			(size 0.4318 0.4318)
			(layers "F.Cu" "F.Mask" "F.Paste")
			(net "GND")
		)
		(pad "V53" smd circle
			(at 6.49732 -18.976086 270)
			(size 0.4318 0.4318)
			(layers "F.Cu" "F.Mask" "F.Paste")
			(net "GND")
		)
		(pad "V55" smd circle
			(at 8.124952 -18.976086 270)
			(size 0.4318 0.4318)
			(layers "F.Cu" "F.Mask" "F.Paste")
			(net "GND")
		)
		(pad "V57" smd circle
			(at 9.752838 -18.976086 270)
			(size 0.4318 0.4318)
			(layers "F.Cu" "F.Mask" "F.Paste")
			(net "GND")
		)
		(pad "V59" smd circle
			(at 11.380724 -18.976086 270)
			(size 0.4318 0.4318)
			(layers "F.Cu" "F.Mask" "F.Paste")
			(net "GND")
		)
		(pad "V61" smd circle
			(at 13.008356 -18.976086 270)
			(size 0.4318 0.4318)
			(layers "F.Cu" "F.Mask" "F.Paste")
			(net "GND")
		)
		(pad "V63" smd circle
			(at 14.635988 -18.976086 270)
			(size 0.4318 0.4318)
			(layers "F.Cu" "F.Mask" "F.Paste")
			(net "GND")
		)
		(pad "V65" smd circle
			(at 16.263874 -18.976086 270)
			(size 0.4318 0.4318)
			(layers "F.Cu" "F.Mask" "F.Paste")
			(net "GND")
		)
		(pad "V67" smd circle
			(at 17.89176 -18.976086 270)
			(size 0.4318 0.4318)
			(layers "F.Cu" "F.Mask" "F.Paste")
			(net "GND")
		)
		(pad "V69" smd circle
			(at 19.519392 -18.976086 270)
			(size 0.4318 0.4318)
			(layers "F.Cu" "F.Mask" "F.Paste")
			(net "GND")
		)
		(pad "V71" smd circle
			(at 21.147278 -18.976086 270)
			(size 0.4318 0.4318)
			(layers "F.Cu" "F.Mask" "F.Paste")
			(net "GND")
		)
		(pad "V73" smd circle
			(at 22.77491 -18.976086 270)
			(size 0.4318 0.4318)
			(layers "F.Cu" "F.Mask" "F.Paste")
			(net "GND")
		)
		(pad "V75" smd circle
			(at 24.402796 -18.976086 270)
			(size 0.4318 0.4318)
			(layers "F.Cu" "F.Mask" "F.Paste")
			(net "GND")
		)
		(pad "V77" smd circle
			(at 26.030682 -18.976086 270)
			(size 0.4318 0.4318)
			(layers "F.Cu" "F.Mask" "F.Paste")
			(net "GND")
		)
		(pad "V79" smd circle
			(at 27.658314 -18.976086 270)
			(size 0.4318 0.4318)
			(layers "F.Cu" "F.Mask" "F.Paste")
			(net "GND")
		)
		(pad "V81" smd circle
			(at 29.2862 -18.976086 270)
			(size 0.4318 0.4318)
			(layers "F.Cu" "F.Mask" "F.Paste")
			(net "UPI_CPU0_CPU1_P2P2_DP<16>")
		)
		(pad "V83" smd circle
			(at 30.914086 -18.976086 270)
			(size 0.4318 0.4318)
			(layers "F.Cu" "F.Mask" "F.Paste")
			(net "UPI_CPU0_CPU1_P2P2_DN<15>")
		)
		(pad "V85" smd circle
			(at 32.541718 -18.976086 270)
			(size 0.4318 0.4318)
			(layers "F.Cu" "F.Mask" "F.Paste")
			(net "P5E_CPU0_PE4_TX_DP<3>")
		)
		(pad "V87" smd circle
			(at 34.169604 -18.976086 270)
			(size 0.4318 0.4318)
			(layers "F.Cu" "F.Mask" "F.Paste")
			(net "GND")
		)
		(pad "V89" smd circle
			(at 35.797236 -18.976086 270)
			(size 0.4318 0.4318)
			(layers "F.Cu" "F.Mask" "F.Paste")
			(net "P5E_CPU0_PE4_RX_DN<3>")
		)
		(pad "V91" smd oval
			(at 37.425122 -18.976086)
			(size 0.381 0.4826)
			(drill
				(offset 0 -0.0508)
			)
			(layers "F.Cu" "F.Mask" "F.Paste")
			(net "GND")
		)
		(pad "W1" smd oval
			(at -37.425122 -18.615914 180)
			(size 0.381 0.4826)
			(drill
				(offset 0 -0.0508)
			)
			(layers "F.Cu" "F.Mask" "F.Paste")
			(net "GND")
		)
		(pad "W3" smd circle
			(at -35.797236 -18.615914 270)
			(size 0.4318 0.4318)
			(layers "F.Cu" "F.Mask" "F.Paste")
			(net "UPI_CPU0_CPU1_P0P1_DP<5>")
		)
		(pad "W5" smd circle
			(at -34.169604 -18.615914 270)
			(size 0.4318 0.4318)
			(layers "F.Cu" "F.Mask" "F.Paste")
			(net "GND")
		)
		(pad "W7" smd circle
			(at -32.541718 -18.615914 270)
			(size 0.4318 0.4318)
			(layers "F.Cu" "F.Mask" "F.Paste")
			(net "UPI_CPU1_CPU0_P1P0_DP<4>")
		)
		(pad "W9" smd circle
			(at -30.914086 -18.615914 270)
			(size 0.4318 0.4318)
			(layers "F.Cu" "F.Mask" "F.Paste")
			(net "GND")
		)
		(pad "W11" smd circle
			(at -29.2862 -18.615914 270)
			(size 0.4318 0.4318)
			(layers "F.Cu" "F.Mask" "F.Paste")
			(net "P5E_CPU0_PE0_RX_DP<4>")
		)
		(pad "W13" smd circle
			(at -27.658314 -18.615914 270)
			(size 0.4318 0.4318)
			(layers "F.Cu" "F.Mask" "F.Paste")
			(net "GND")
		)
		(pad "W15" smd circle
			(at -26.030682 -18.615914 270)
			(size 0.4318 0.4318)
			(layers "F.Cu" "F.Mask" "F.Paste")
			(net "P5E_CPU0_PE0_TX_DP<3>")
		)
		(pad "W17" smd circle
			(at -24.402796 -18.615914 270)
			(size 0.4318 0.4318)
			(layers "F.Cu" "F.Mask" "F.Paste")
			(net "NC_CPU0_HBM1_VIEWDIG0")
		)
		(pad "W19" smd circle
			(at -22.77491 -18.615914 270)
			(size 0.4318 0.4318)
			(layers "F.Cu" "F.Mask" "F.Paste")
			(net "M_C_CPU0_SB_DQ<23>")
		)
		(pad "W21" smd circle
			(at -21.147278 -18.615914 270)
			(size 0.4318 0.4318)
			(layers "F.Cu" "F.Mask" "F.Paste")
			(net "M_C_CPU0_SB_DQS_DN<7>")
		)
		(pad "W23" smd circle
			(at -19.519392 -18.615914 270)
			(size 0.4318 0.4318)
			(layers "F.Cu" "F.Mask" "F.Paste")
			(net "M_C_CPU0_SB_DQ<18>")
		)
		(pad "W25" smd circle
			(at -17.89176 -18.615914 270)
			(size 0.4318 0.4318)
			(layers "F.Cu" "F.Mask" "F.Paste")
			(net "M_B_CPU0_SB_DQ<7>")
		)
		(pad "W27" smd circle
			(at -16.263874 -18.615914 270)
			(size 0.4318 0.4318)
			(layers "F.Cu" "F.Mask" "F.Paste")
			(net "M_B_CPU0_SB_DQS_DN<5>")
		)
		(pad "W29" smd circle
			(at -14.635988 -18.615914 270)
			(size 0.4318 0.4318)
			(layers "F.Cu" "F.Mask" "F.Paste")
			(net "M_B_CPU0_SB_DQ<2>")
		)
		(pad "W31" smd circle
			(at -13.008356 -18.615914 270)
			(size 0.4318 0.4318)
			(layers "F.Cu" "F.Mask" "F.Paste")
			(net "M_C_CPU0_SB_CB<3>")
		)
		(pad "W33" smd circle
			(at -11.380724 -18.615914 270)
			(size 0.4318 0.4318)
			(layers "F.Cu" "F.Mask" "F.Paste")
			(net "M_C_CPU0_SB_DQS_DN<4>")
		)
		(pad "W35" smd circle
			(at -9.752838 -18.615914 270)
			(size 0.4318 0.4318)
			(layers "F.Cu" "F.Mask" "F.Paste")
			(net "M_C_CPU0_SB_CB<6>")
		)
		(pad "W37" smd circle
			(at -8.124952 -18.615914 270)
			(size 0.4318 0.4318)
			(layers "F.Cu" "F.Mask" "F.Paste")
			(net "M_C_CPU0_SB_CS_N<3>")
		)
		(pad "W39" smd circle
			(at -6.49732 -18.615914 270)
			(size 0.4318 0.4318)
			(layers "F.Cu" "F.Mask" "F.Paste")
			(net "GND")
		)
		(pad "W41" smd circle
			(at -4.869434 -18.615914 270)
			(size 0.4318 0.4318)
			(layers "F.Cu" "F.Mask" "F.Paste")
			(net "M_C_CPU0_SB_CA<3>")
		)
		(pad "W43" smd circle
			(at -3.241802 -18.615914 270)
			(size 0.4318 0.4318)
			(layers "F.Cu" "F.Mask" "F.Paste")
			(net "M_B_CPU0_SA_PAR")
		)
		(pad "W45" smd circle
			(at -1.613916 -18.615914 270)
			(size 0.4318 0.4318)
			(layers "F.Cu" "F.Mask" "F.Paste")
			(net "M_B_CPU0_CLK_DN<1>")
		)
		(pad "W48" smd circle
			(at 2.427732 -18.505932 270)
			(size 0.4318 0.4318)
			(layers "F.Cu" "F.Mask" "F.Paste")
			(net "M_C_CPU0_SB_CA<0>")
		)
		(pad "W50" smd circle
			(at 4.055618 -18.505932 270)
			(size 0.4318 0.4318)
			(layers "F.Cu" "F.Mask" "F.Paste")
			(net "M_C_CPU0_SA_CA<5>")
		)
		(pad "W52" smd circle
			(at 5.68325 -18.505932 270)
			(size 0.4318 0.4318)
			(layers "F.Cu" "F.Mask" "F.Paste")
			(net "GND")
		)
		(pad "W54" smd circle
			(at 7.311136 -18.505932 270)
			(size 0.4318 0.4318)
			(layers "F.Cu" "F.Mask" "F.Paste")
			(net "M_C_CPU0_SA_CS_N<2>")
		)
		(pad "W56" smd circle
			(at 8.939022 -18.505932 270)
			(size 0.4318 0.4318)
			(layers "F.Cu" "F.Mask" "F.Paste")
			(net "M_B_CPU0_SA_DQ<31>")
		)
		(pad "W58" smd circle
			(at 10.566654 -18.505932 270)
			(size 0.4318 0.4318)
			(layers "F.Cu" "F.Mask" "F.Paste")
			(net "M_B_CPU0_SA_DQS_DP<8>")
		)
		(pad "W60" smd circle
			(at 12.19454 -18.505932 270)
			(size 0.4318 0.4318)
			(layers "F.Cu" "F.Mask" "F.Paste")
			(net "M_B_CPU0_SA_DQ<26>")
		)
		(pad "W62" smd circle
			(at 13.822426 -18.505932 270)
			(size 0.4318 0.4318)
			(layers "F.Cu" "F.Mask" "F.Paste")
			(net "M_C_CPU0_SA_DQ<23>")
		)
		(pad "W64" smd circle
			(at 15.450058 -18.505932 270)
			(size 0.4318 0.4318)
			(layers "F.Cu" "F.Mask" "F.Paste")
			(net "M_C_CPU0_SA_DQS_DP<7>")
		)
		(pad "W66" smd circle
			(at 17.07769 -18.505932 270)
			(size 0.4318 0.4318)
			(layers "F.Cu" "F.Mask" "F.Paste")
			(net "M_C_CPU0_SA_DQ<18>")
		)
		(pad "W68" smd circle
			(at 18.705576 -18.505932 270)
			(size 0.4318 0.4318)
			(layers "F.Cu" "F.Mask" "F.Paste")
			(net "M_B_CPU0_SA_DQ<15>")
		)
		(pad "W70" smd circle
			(at 20.333462 -18.505932 270)
			(size 0.4318 0.4318)
			(layers "F.Cu" "F.Mask" "F.Paste")
			(net "M_B_CPU0_SA_DQS_DP<6>")
		)
		(pad "W72" smd circle
			(at 21.961094 -18.505932 270)
			(size 0.4318 0.4318)
			(layers "F.Cu" "F.Mask" "F.Paste")
			(net "M_B_CPU0_SA_DQ<10>")
		)
		(pad "W74" smd circle
			(at 23.58898 -18.505932 270)
			(size 0.4318 0.4318)
			(layers "F.Cu" "F.Mask" "F.Paste")
			(net "M_C_CPU0_SA_DQ<7>")
		)
		(pad "W76" smd circle
			(at 25.216612 -18.505932 270)
			(size 0.4318 0.4318)
			(layers "F.Cu" "F.Mask" "F.Paste")
			(net "M_C_CPU0_SA_DQS_DN<5>")
		)
		(pad "W78" smd circle
			(at 26.844498 -18.505932 270)
			(size 0.4318 0.4318)
			(layers "F.Cu" "F.Mask" "F.Paste")
			(net "M_C_CPU0_SA_DQ<2>")
		)
		(pad "W80" smd circle
			(at 28.472384 -18.505932 270)
			(size 0.4318 0.4318)
			(layers "F.Cu" "F.Mask" "F.Paste")
			(net "PVCCFA_EHV_FIVRA_CPU0")
		)
		(pad "W82" smd circle
			(at 30.100016 -18.505932 270)
			(size 0.4318 0.4318)
			(layers "F.Cu" "F.Mask" "F.Paste")
			(net "UPI_CPU0_CPU1_P2P2_DP<14>")
		)
		(pad "W84" smd circle
			(at 31.727902 -18.505932 270)
			(size 0.4318 0.4318)
			(layers "F.Cu" "F.Mask" "F.Paste")
			(net "GND")
		)
		(pad "W86" smd circle
			(at 33.355534 -18.505932 270)
			(size 0.4318 0.4318)
			(layers "F.Cu" "F.Mask" "F.Paste")
			(net "P5E_CPU0_PE4_TX_DN<4>")
		)
		(pad "W88" smd circle
			(at 34.98342 -18.505932 270)
			(size 0.4318 0.4318)
			(layers "F.Cu" "F.Mask" "F.Paste")
			(net "GND")
		)
		(pad "W90" smd circle
			(at 36.611306 -18.505932 270)
			(size 0.4318 0.4318)
			(layers "F.Cu" "F.Mask" "F.Paste")
			(net "P5E_CPU0_PE4_RX_DP<4>")
		)
		(pad "Y2" smd circle
			(at -36.611306 -18.146268 270)
			(size 0.4318 0.4318)
			(layers "F.Cu" "F.Mask" "F.Paste")
			(net "UPI_CPU0_CPU1_P0P1_DN<5>")
		)
		(pad "Y4" smd circle
			(at -34.98342 -18.146268 270)
			(size 0.4318 0.4318)
			(layers "F.Cu" "F.Mask" "F.Paste")
			(net "GND")
		)
		(pad "Y6" smd circle
			(at -33.355534 -18.146268 270)
			(size 0.4318 0.4318)
			(layers "F.Cu" "F.Mask" "F.Paste")
			(net "UPI_CPU1_CPU0_P1P0_DN<5>")
		)
		(pad "Y8" smd circle
			(at -31.727902 -18.146268 270)
			(size 0.4318 0.4318)
			(layers "F.Cu" "F.Mask" "F.Paste")
			(net "GND")
		)
		(pad "Y10" smd circle
			(at -30.100016 -18.146268 270)
			(size 0.4318 0.4318)
			(layers "F.Cu" "F.Mask" "F.Paste")
			(net "P5E_CPU0_PE0_RX_DP<5>")
		)
		(pad "Y12" smd circle
			(at -28.472384 -18.146268 270)
			(size 0.4318 0.4318)
			(layers "F.Cu" "F.Mask" "F.Paste")
			(net "GND")
		)
		(pad "Y14" smd circle
			(at -26.844498 -18.146268 270)
			(size 0.4318 0.4318)
			(layers "F.Cu" "F.Mask" "F.Paste")
			(net "P5E_CPU0_PE0_TX_DP<4>")
		)
		(pad "Y16" smd circle
			(at -25.216612 -18.146268 270)
			(size 0.4318 0.4318)
			(layers "F.Cu" "F.Mask" "F.Paste")
			(net "GND")
		)
		(pad "Y18" smd circle
			(at -23.58898 -18.146268 270)
			(size 0.4318 0.4318)
			(layers "F.Cu" "F.Mask" "F.Paste")
			(net "GND")
		)
		(pad "Y20" smd circle
			(at -21.961094 -18.146268 270)
			(size 0.4318 0.4318)
			(layers "F.Cu" "F.Mask" "F.Paste")
			(net "M_C_CPU0_SB_DQ<22>")
		)
		(pad "Y22" smd circle
			(at -20.333462 -18.146268 270)
			(size 0.4318 0.4318)
			(layers "F.Cu" "F.Mask" "F.Paste")
			(net "M_C_CPU0_SB_DQ<19>")
		)
		(pad "Y24" smd circle
			(at -18.705576 -18.146268 270)
			(size 0.4318 0.4318)
			(layers "F.Cu" "F.Mask" "F.Paste")
			(net "GND")
		)
		(pad "Y26" smd circle
			(at -17.07769 -18.146268 270)
			(size 0.4318 0.4318)
			(layers "F.Cu" "F.Mask" "F.Paste")
			(net "M_B_CPU0_SB_DQ<6>")
		)
		(pad "Y28" smd circle
			(at -15.450058 -18.146268 270)
			(size 0.4318 0.4318)
			(layers "F.Cu" "F.Mask" "F.Paste")
			(net "M_B_CPU0_SB_DQ<3>")
		)
		(pad "Y30" smd circle
			(at -13.822426 -18.146268 270)
			(size 0.4318 0.4318)
			(layers "F.Cu" "F.Mask" "F.Paste")
			(net "GND")
		)
		(pad "Y32" smd circle
			(at -12.19454 -18.146268 270)
			(size 0.4318 0.4318)
			(layers "F.Cu" "F.Mask" "F.Paste")
			(net "M_C_CPU0_SB_CB<2>")
		)
		(pad "Y34" smd circle
			(at -10.566654 -18.146268 270)
			(size 0.4318 0.4318)
			(layers "F.Cu" "F.Mask" "F.Paste")
			(net "M_C_CPU0_SB_CB<7>")
		)
		(pad "Y36" smd circle
			(at -8.939022 -18.146268 270)
			(size 0.4318 0.4318)
			(layers "F.Cu" "F.Mask" "F.Paste")
			(net "GND")
		)
		(pad "Y38" smd circle
			(at -7.311136 -18.146268 270)
			(size 0.4318 0.4318)
			(layers "F.Cu" "F.Mask" "F.Paste")
			(net "M_C_CPU0_SB_CS_N<2>")
		)
	)
)
